(kicad_pcb
	(version 20260206)
	(generator "pcbnew")
	(generator_version "10.0")
	(general
		(thickness 1.6)
		(legacy_teardrops no)
	)
	(paper "A4")
	(title_block
		(title "Bryce Canyon_SCC_16316-1_OCP.brd")
		(comment 1 "Bryce Canyon / footprints 1338-1346 of 1561")
	)
	(layers
		(0 "F.Cu" signal "TOP")
		(4 "In1.Cu" signal "L2GND")
		(6 "In2.Cu" signal "L3")
		(8 "In3.Cu" signal "L4VCC")
		(10 "In4.Cu" signal "L5VCC")
		(12 "In5.Cu" signal "L6")
		(14 "In6.Cu" signal "L7GND")
		(2 "B.Cu" signal "BOTTOM")
		(9 "F.Adhes" user "F.Adhesive")
		(11 "B.Adhes" user "B.Adhesive")
		(13 "F.Paste" user "Package Geometry/Pastemask Top")
		(15 "B.Paste" user "Package Geometry/Pastemask Bottom")
		(5 "F.SilkS" user "Ref Des/Silkscreen Top")
		(7 "B.SilkS" user "Ref Des/Silkscreen Bottom")
		(1 "F.Mask" user "Board Geometry/Soldermask Top")
		(3 "B.Mask" user "Board Geometry/Soldermask Bottom")
		(17 "Dwgs.User" user "User.Drawings")
		(19 "Cmts.User" user "User.Comments")
		(21 "Eco1.User" user "User.Eco1")
		(23 "Eco2.User" user "User.Eco2")
		(25 "Edge.Cuts" user "Board Geometry/Outline")
		(27 "Margin" user)
		(31 "F.CrtYd" user "Package Geometry/Place Bound Top")
		(29 "B.CrtYd" user "Package Geometry/Place Bound Bottom")
		(35 "F.Fab" user "Ref Des/Assembly Top")
		(33 "B.Fab" user "Ref Des/Assembly Bottom")
	)
	(footprint ""
		(layer "B.Cu")
		(at 120.5738 -63.2968 -90)
		(property "Reference" "C217"
			(at 0 0 90)
			(layer "B.SilkS")
			(hide yes)
			(effects
				(font
					(size 1.27 1.27)
				)
				(justify mirror)
			)
		)
		(property "Value" "SCD1U16V2KX-3GP"
			(at -1.1811 -2.7051 270)
			(unlocked yes)
			(layer "B.Fab")
			(hide yes)
			(effects
				(font
					(size 1.016 1.016)
					(thickness 0.1524)
				)
				(justify mirror)
			)
		)
		(property "Device Type" "C402H22"
			(at -1.1811 -4.2291 270)
			(unlocked yes)
			(layer "B.Fab")
			(hide yes)
			(effects
				(font
					(size 1.016 1.016)
					(thickness 0.1524)
				)
				(justify mirror)
			)
		)
		(duplicate_pad_numbers_are_jumpers no)
		(fp_rect
			(start 0.4318 0.9525)
			(end -0.4318 -0.9525)
			(stroke
				(width 0)
				(type default)
			)
			(fill no)
			(layer "B.CrtYd")
		)
		(fp_rect
			(start 0.4318 0.9525)
			(end -0.4318 -0.9525)
			(stroke
				(width 0)
				(type default)
			)
			(fill no)
			(layer "B.Fab")
		)
		(pad "1" smd custom
			(at 0 -0.4445 90)
			(size 0.1524 0.1524)
			(layers "B.Cu" "B.Mask" "B.Paste")
			(net "GB_VDDH")
			(options
				(clearance outline)
				(anchor circle)
			)
			(primitives
				(gr_poly
					(pts
						(arc
							(start 0.3048 0.2032)
							(mid 0.275042 0.275042)
							(end 0.2032 0.3048)
						)
						(arc
							(start -0.2032 0.3048)
							(mid -0.275042 0.275042)
							(end -0.3048 0.2032)
						)
						(arc
							(start -0.3048 -0.2032)
							(mid -0.275042 -0.275042)
							(end -0.2032 -0.3048)
						)
						(arc
							(start 0.2032 -0.3048)
							(mid 0.275042 -0.275042)
							(end 0.3048 -0.2032)
						)
					)
					(width 0)
					(fill yes)
				)
			)
		)
		(pad "2" smd custom
			(at 0 0.4445 90)
			(size 0.1524 0.1524)
			(layers "B.Cu" "B.Mask" "B.Paste")
			(net "GND")
			(options
				(clearance outline)
				(anchor circle)
			)
			(primitives
				(gr_poly
					(pts
						(arc
							(start 0.3048 0.2032)
							(mid 0.275042 0.275042)
							(end 0.2032 0.3048)
						)
						(arc
							(start -0.2032 0.3048)
							(mid -0.275042 0.275042)
							(end -0.3048 0.2032)
						)
						(arc
							(start -0.3048 -0.2032)
							(mid -0.275042 -0.275042)
							(end -0.2032 -0.3048)
						)
						(arc
							(start 0.2032 -0.3048)
							(mid 0.275042 -0.275042)
							(end 0.3048 -0.2032)
						)
					)
					(width 0)
					(fill yes)
				)
			)
		)
	)
	(footprint ""
		(layer "B.Cu")
		(at 129.54 -89.7382)
		(property "Reference" "R65"
			(at 0 0 0)
			(layer "B.SilkS")
			(hide yes)
			(effects
				(font
					(size 1.27 1.27)
				)
				(justify mirror)
			)
		)
		(property "Value" "4K7R2F-GP"
			(at -0.064008 -3.993896 0)
			(unlocked yes)
			(layer "B.Fab")
			(hide yes)
			(effects
				(font
					(size 1.016 1.016)
					(thickness 0.1524)
				)
				(justify mirror)
			)
		)
		(property "Device Type" "R402H16"
			(at -0.064008 -5.517896 0)
			(unlocked yes)
			(layer "B.Fab")
			(hide yes)
			(effects
				(font
					(size 1.016 1.016)
					(thickness 0.1524)
				)
				(justify mirror)
			)
		)
		(duplicate_pad_numbers_are_jumpers no)
		(fp_line
			(start -0.508 -0.9398)
			(end 0.508 -0.9398)
			(stroke
				(width 0.1524)
				(type default)
			)
			(layer "B.SilkS")
		)
		(fp_line
			(start 0.508 -0.9398)
			(end 0.508 0.9398)
			(stroke
				(width 0.1524)
				(type default)
			)
			(layer "B.SilkS")
		)
		(fp_rect
			(start 0.508 0.9398)
			(end -0.508 -0.9398)
			(stroke
				(width 0)
				(type default)
			)
			(fill no)
			(layer "B.CrtYd")
		)
		(fp_rect
			(start 0.508 0.9398)
			(end -0.508 -0.9398)
			(stroke
				(width 0)
				(type default)
			)
			(fill no)
			(layer "B.Fab")
		)
		(pad "1" smd custom
			(at 0 -0.4445 180)
			(size 0.1397 0.1397)
			(layers "B.Cu" "B.Mask" "B.Paste")
			(net "P1V8_E")
			(options
				(clearance outline)
				(anchor circle)
			)
			(primitives
				(gr_poly
					(pts
						(arc
							(start -0.1778 0.2794)
							(mid -0.249642 0.249642)
							(end -0.2794 0.1778)
						)
						(arc
							(start -0.2794 -0.1778)
							(mid -0.249642 -0.249642)
							(end -0.1778 -0.2794)
						)
						(arc
							(start 0.1778 -0.2794)
							(mid 0.249642 -0.249642)
							(end 0.2794 -0.1778)
						)
						(arc
							(start 0.2794 0.1778)
							(mid 0.249642 0.249642)
							(end 0.1778 0.2794)
						)
					)
					(width 0)
					(fill yes)
				)
			)
		)
		(pad "2" smd custom
			(at 0 0.4445 180)
			(size 0.1397 0.1397)
			(layers "B.Cu" "B.Mask" "B.Paste")
			(net "I2C_CLIP_SDA7_LS")
			(options
				(clearance outline)
				(anchor circle)
			)
			(primitives
				(gr_poly
					(pts
						(arc
							(start -0.1778 0.2794)
							(mid -0.249642 0.249642)
							(end -0.2794 0.1778)
						)
						(arc
							(start -0.2794 -0.1778)
							(mid -0.249642 -0.249642)
							(end -0.1778 -0.2794)
						)
						(arc
							(start 0.1778 -0.2794)
							(mid 0.249642 -0.249642)
							(end 0.2794 -0.1778)
						)
						(arc
							(start 0.2794 0.1778)
							(mid 0.249642 0.249642)
							(end 0.1778 0.2794)
						)
					)
					(width 0)
					(fill yes)
				)
			)
		)
	)
	(footprint ""
		(layer "B.Cu")
		(at 176.977294 -46.096682 180)
		(property "Reference" "C405"
			(at 0 0 0)
			(layer "B.SilkS")
			(hide yes)
			(effects
				(font
					(size 1.27 1.27)
				)
				(justify mirror)
			)
		)
		(property "Value" "SC10U6D3V5KX-4GP"
			(at 0.0762 -6.1214 180)
			(unlocked yes)
			(layer "B.Fab")
			(hide yes)
			(effects
				(font
					(size 1.016 1.016)
					(thickness 0.1524)
				)
				(justify mirror)
			)
		)
		(property "Device Type" "C805H58"
			(at 0.0762 -8.1534 180)
			(unlocked yes)
			(layer "B.Fab")
			(hide yes)
			(effects
				(font
					(size 1.016 1.016)
					(thickness 0.1524)
				)
				(justify mirror)
			)
		)
		(duplicate_pad_numbers_are_jumpers no)
		(fp_line
			(start -0.635 0)
			(end 0.635 0)
			(stroke
				(width 0.508)
				(type default)
			)
			(layer "B.SilkS")
		)
		(fp_rect
			(start 0.9652 1.778)
			(end -0.9652 -1.778)
			(stroke
				(width 0)
				(type default)
			)
			(fill no)
			(layer "B.CrtYd")
		)
		(fp_poly
			(pts
				(xy 0.9652 -1.778) (xy -0.9652 -1.778) (xy -0.9652 1.778) (xy 0.9652 1.778)
			)
			(stroke
				(width 0)
				(type default)
			)
			(fill no)
			(layer "B.Fab")
		)
		(pad "1" smd rect
			(at 0 -0.9652)
			(size 1.397 1.143)
			(layers "B.Cu" "B.Mask" "B.Paste")
			(net "P0V975")
		)
		(pad "2" smd rect
			(at 0 0.9652)
			(size 1.397 1.143)
			(layers "B.Cu" "B.Mask" "B.Paste")
			(net "GND")
		)
	)
	(footprint ""
		(layer "B.Cu")
		(at 116.7638 -59.4487)
		(property "Reference" "C512"
			(at 0 0 0)
			(layer "B.SilkS")
			(hide yes)
			(effects
				(font
					(size 1.27 1.27)
				)
				(justify mirror)
			)
		)
		(property "Value" "SCD1U6D3V1KX-GP"
			(at 2.8321 -1.7399 0)
			(unlocked yes)
			(layer "B.Fab")
			(hide yes)
			(effects
				(font
					(size 1.016 1.016)
					(thickness 0.1524)
				)
				(justify mirror)
			)
		)
		(property "Device Type" "C0201H13"
			(at 2.8321 -3.2639 0)
			(unlocked yes)
			(layer "B.Fab")
			(hide yes)
			(effects
				(font
					(size 1.016 1.016)
					(thickness 0.1524)
				)
				(justify mirror)
			)
		)
		(duplicate_pad_numbers_are_jumpers no)
		(fp_rect
			(start 0.2794 0.6477)
			(end -0.2794 -0.6477)
			(stroke
				(width 0)
				(type default)
			)
			(fill no)
			(layer "B.CrtYd")
		)
		(fp_rect
			(start 0.2794 0.6477)
			(end -0.2794 -0.6477)
			(stroke
				(width 0)
				(type default)
			)
			(fill no)
			(layer "B.Fab")
		)
		(pad "1" smd custom
			(at 0 -0.2794 180)
			(size 0.0762 0.0762)
			(layers "B.Cu" "B.Mask" "B.Paste")
			(net "GB_VDDA")
			(options
				(clearance outline)
				(anchor circle)
			)
			(primitives
				(gr_poly
					(pts
						(arc
							(start 0.1524 0.127)
							(mid 0.137521 0.162921)
							(end 0.1016 0.1778)
						)
						(arc
							(start -0.1016 0.1778)
							(mid -0.137521 0.162921)
							(end -0.1524 0.127)
						)
						(arc
							(start -0.1524 -0.127)
							(mid -0.137521 -0.162921)
							(end -0.1016 -0.1778)
						)
						(arc
							(start 0.1016 -0.1778)
							(mid 0.137521 -0.162921)
							(end 0.1524 -0.127)
						)
					)
					(width 0)
					(fill yes)
				)
			)
		)
		(pad "2" smd custom
			(at 0 0.2794 180)
			(size 0.0762 0.0762)
			(layers "B.Cu" "B.Mask" "B.Paste")
			(net "GND")
			(options
				(clearance outline)
				(anchor circle)
			)
			(primitives
				(gr_poly
					(pts
						(arc
							(start 0.1524 0.127)
							(mid 0.137521 0.162921)
							(end 0.1016 0.1778)
						)
						(arc
							(start -0.1016 0.1778)
							(mid -0.137521 0.162921)
							(end -0.1524 0.127)
						)
						(arc
							(start -0.1524 -0.127)
							(mid -0.137521 -0.162921)
							(end -0.1016 -0.1778)
						)
						(arc
							(start 0.1016 -0.1778)
							(mid 0.137521 -0.162921)
							(end 0.1524 -0.127)
						)
					)
					(width 0)
					(fill yes)
				)
			)
		)
	)
	(footprint ""
		(layer "B.Cu")
		(at 106.254042 -72.605392)
		(property "Reference" "C120"
			(at 0 0 0)
			(layer "B.SilkS")
			(hide yes)
			(effects
				(font
					(size 1.27 1.27)
				)
				(justify mirror)
			)
		)
		(property "Value" "SC10U6D3V2MX-GP-U"
			(at 1.524 -1.905 0)
			(unlocked yes)
			(layer "B.Fab")
			(hide yes)
			(effects
				(font
					(size 1.016 1.016)
					(thickness 0.1524)
				)
				(justify mirror)
			)
		)
		(property "Device Type" "C402-TO0D2H28"
			(at 1.524 -3.429 0)
			(unlocked yes)
			(layer "B.Fab")
			(hide yes)
			(effects
				(font
					(size 1.016 1.016)
					(thickness 0.1524)
				)
				(justify mirror)
			)
		)
		(duplicate_pad_numbers_are_jumpers no)
		(fp_rect
			(start 0.4826 0.889)
			(end -0.4826 -0.889)
			(stroke
				(width 0)
				(type default)
			)
			(fill no)
			(layer "B.CrtYd")
		)
		(fp_rect
			(start 0.4826 0.889)
			(end -0.4826 -0.889)
			(stroke
				(width 0)
				(type default)
			)
			(fill no)
			(layer "B.Fab")
		)
		(pad "1" smd custom
			(at 0 -0.4572 180)
			(size 0.1524 0.1524)
			(layers "B.Cu" "B.Mask" "B.Paste")
			(net "P1V8_E")
			(options
				(clearance outline)
				(anchor circle)
			)
			(primitives
				(gr_poly
					(pts
						(arc
							(start -0.254 -0.3048)
							(mid -0.325842 -0.275042)
							(end -0.3556 -0.2032)
						)
						(arc
							(start -0.3556 0.2032)
							(mid -0.325842 0.275042)
							(end -0.254 0.3048)
						)
						(arc
							(start 0.254 0.3048)
							(mid 0.325842 0.275042)
							(end 0.3556 0.2032)
						)
						(arc
							(start 0.3556 -0.2032)
							(mid 0.325842 -0.275042)
							(end 0.254 -0.3048)
						)
					)
					(width 0)
					(fill yes)
				)
			)
		)
		(pad "2" smd custom
			(at 0 0.4572 180)
			(size 0.1524 0.1524)
			(layers "B.Cu" "B.Mask" "B.Paste")
			(net "GND")
			(options
				(clearance outline)
				(anchor circle)
			)
			(primitives
				(gr_poly
					(pts
						(arc
							(start -0.254 -0.3048)
							(mid -0.325842 -0.275042)
							(end -0.3556 -0.2032)
						)
						(arc
							(start -0.3556 0.2032)
							(mid -0.325842 0.275042)
							(end -0.254 0.3048)
						)
						(arc
							(start 0.254 0.3048)
							(mid 0.325842 0.275042)
							(end 0.3556 0.2032)
						)
						(arc
							(start 0.3556 -0.2032)
							(mid 0.325842 -0.275042)
							(end 0.254 -0.3048)
						)
					)
					(width 0)
					(fill yes)
				)
			)
		)
	)
	(footprint ""
		(layer "B.Cu")
		(at 167.259 -93.98 180)
		(property "Reference" "PSP2"
			(at 0 0 0)
			(layer "B.SilkS")
			(hide yes)
			(effects
				(font
					(size 1.27 1.27)
				)
				(justify mirror)
			)
		)
		(property "Value" "COPPER-CLOSE-GP-U"
			(at -0.0762 -2.8702 180)
			(unlocked yes)
			(layer "B.Fab")
			(hide yes)
			(effects
				(font
					(size 1.016 1.016)
					(thickness 0.1524)
				)
				(justify mirror)
			)
		)
		(property "Device Type" "CON2C-U"
			(at -0.0762 -4.3942 180)
			(unlocked yes)
			(layer "B.Fab")
			(hide yes)
			(effects
				(font
					(size 1.016 1.016)
					(thickness 0.1524)
				)
				(justify mirror)
			)
		)
		(duplicate_pad_numbers_are_jumpers no)
		(fp_rect
			(start 0.9398 0.9652)
			(end -0.9398 -0.9652)
			(stroke
				(width 0)
				(type default)
			)
			(fill no)
			(layer "B.CrtYd")
		)
		(fp_rect
			(start 0.9398 0.9652)
			(end -0.9398 -0.9652)
			(stroke
				(width 0)
				(type default)
			)
			(fill no)
			(layer "B.Fab")
		)
		(pad "1" smd custom
			(at 0 -0.5334)
			(size 0.17145 0.17145)
			(layers "B.Cu" "B.Mask" "B.Paste")
			(net "GND")
			(options
				(clearance outline)
				(anchor circle)
			)
			(primitives
				(gr_poly
					(pts
						(xy -0.127 -0.3429) (xy -0.127 -0.1651) (xy -0.635 0.3429) (xy 0.635 0.3429) (xy 0.127 -0.1651)
						(xy 0.127 -0.3429)
					)
					(width 0)
					(fill yes)
				)
			)
		)
		(pad "2" smd custom
			(at 0 0.5334)
			(size 0.17145 0.17145)
			(layers "B.Cu" "B.Mask" "B.Paste")
			(net "AGND_P0V975")
			(options
				(clearance outline)
				(anchor circle)
			)
			(primitives
				(gr_poly
					(pts
						(xy -0.635 -0.3429) (xy -0.127 0.1651) (xy -0.127 0.3429) (xy 0.127 0.3429) (xy 0.127 0.1651)
						(xy 0.635 -0.3429)
					)
					(width 0)
					(fill yes)
				)
			)
		)
	)
	(footprint ""
		(layer "B.Cu")
		(at 114.681 -53.467 180)
		(property "Reference" "C233"
			(at 0 0 0)
			(layer "B.SilkS")
			(hide yes)
			(effects
				(font
					(size 1.27 1.27)
				)
				(justify mirror)
			)
		)
		(property "Value" "SCD1U6D3V1KX-GP"
			(at 2.8321 -1.7399 180)
			(unlocked yes)
			(layer "B.Fab")
			(hide yes)
			(effects
				(font
					(size 1.016 1.016)
					(thickness 0.1524)
				)
				(justify mirror)
			)
		)
		(property "Device Type" "C0201H13"
			(at 2.8321 -3.2639 180)
			(unlocked yes)
			(layer "B.Fab")
			(hide yes)
			(effects
				(font
					(size 1.016 1.016)
					(thickness 0.1524)
				)
				(justify mirror)
			)
		)
		(duplicate_pad_numbers_are_jumpers no)
		(fp_rect
			(start 0.2794 0.6477)
			(end -0.2794 -0.6477)
			(stroke
				(width 0)
				(type default)
			)
			(fill no)
			(layer "B.CrtYd")
		)
		(fp_rect
			(start 0.2794 0.6477)
			(end -0.2794 -0.6477)
			(stroke
				(width 0)
				(type default)
			)
			(fill no)
			(layer "B.Fab")
		)
		(pad "1" smd custom
			(at 0 -0.2794)
			(size 0.0762 0.0762)
			(layers "B.Cu" "B.Mask" "B.Paste")
			(net "GB_VDDA")
			(options
				(clearance outline)
				(anchor circle)
			)
			(primitives
				(gr_poly
					(pts
						(arc
							(start 0.1524 0.127)
							(mid 0.137521 0.162921)
							(end 0.1016 0.1778)
						)
						(arc
							(start -0.1016 0.1778)
							(mid -0.137521 0.162921)
							(end -0.1524 0.127)
						)
						(arc
							(start -0.1524 -0.127)
							(mid -0.137521 -0.162921)
							(end -0.1016 -0.1778)
						)
						(arc
							(start 0.1016 -0.1778)
							(mid 0.137521 -0.162921)
							(end 0.1524 -0.127)
						)
					)
					(width 0)
					(fill yes)
				)
			)
		)
		(pad "2" smd custom
			(at 0 0.2794)
			(size 0.0762 0.0762)
			(layers "B.Cu" "B.Mask" "B.Paste")
			(net "GND")
			(options
				(clearance outline)
				(anchor circle)
			)
			(primitives
				(gr_poly
					(pts
						(arc
							(start 0.1524 0.127)
							(mid 0.137521 0.162921)
							(end 0.1016 0.1778)
						)
						(arc
							(start -0.1016 0.1778)
							(mid -0.137521 0.162921)
							(end -0.1524 0.127)
						)
						(arc
							(start -0.1524 -0.127)
							(mid -0.137521 -0.162921)
							(end -0.1016 -0.1778)
						)
						(arc
							(start 0.1016 -0.1778)
							(mid 0.137521 -0.162921)
							(end 0.1524 -0.127)
						)
					)
					(width 0)
					(fill yes)
				)
			)
		)
	)
	(footprint ""
		(layer "B.Cu")
		(at 189.5856 -34.1884 90)
		(property "Reference" "TP93"
			(at 0 0 90)
			(layer "B.SilkS")
			(hide yes)
			(effects
				(font
					(size 1.27 1.27)
				)
				(justify mirror)
			)
		)
		(property "Value" "TPAD28-2-GP"
			(at 0.0127 -1.6637 90)
			(unlocked yes)
			(layer "B.Fab")
			(hide yes)
			(effects
				(font
					(size 1.016 1.016)
					(thickness 0.1524)
				)
				(justify mirror)
			)
		)
		(property "Device Type" "TPAD28"
			(at 0.0127 -3.1877 90)
			(unlocked yes)
			(layer "B.Fab")
			(hide yes)
			(effects
				(font
					(size 1.016 1.016)
					(thickness 0.1524)
				)
				(justify mirror)
			)
		)
		(duplicate_pad_numbers_are_jumpers no)
		(fp_poly
			(pts
				(arc
					(start 0 0.3556)
					(mid 0 -0.3556)
					(end 0 0.3556)
				)
			)
			(stroke
				(width 0)
				(type default)
			)
			(fill no)
			(layer "B.CrtYd")
		)
		(fp_poly
			(pts
				(arc
					(start 0 0.6096)
					(mid 0 -0.6096)
					(end 0 0.6096)
				)
			)
			(stroke
				(width 0)
				(type default)
			)
			(fill no)
			(layer "B.Fab")
		)
		(pad "1" smd circle
			(at 0 0 270)
			(size 0.7112 0.7112)
			(layers "B.Cu" "B.Mask" "B.Paste")
			(net "IOC_GPIO_33")
		)
	)
	(footprint ""
		(layer "B.Cu")
		(at 96.497394 -55.141368 90)
		(property "Reference" "C96"
			(at 0 0 90)
			(layer "B.SilkS")
			(hide yes)
			(effects
				(font
					(size 1.27 1.27)
				)
				(justify mirror)
			)
		)
		(property "Value" "SCD01U16V1KX-GP"
			(at 2.8321 -1.7399 90)
			(unlocked yes)
			(layer "B.Fab")
			(hide yes)
			(effects
				(font
					(size 1.016 1.016)
					(thickness 0.1524)
				)
				(justify mirror)
			)
		)
		(property "Device Type" "C0201H13"
			(at 2.8321 -3.2639 90)
			(unlocked yes)
			(layer "B.Fab")
			(hide yes)
			(effects
				(font
					(size 1.016 1.016)
					(thickness 0.1524)
				)
				(justify mirror)
			)
		)
		(duplicate_pad_numbers_are_jumpers no)
		(fp_rect
			(start 0.2794 0.6477)
			(end -0.2794 -0.6477)
			(stroke
				(width 0)
				(type default)
			)
			(fill no)
			(layer "B.CrtYd")
		)
		(fp_rect
			(start 0.2794 0.6477)
			(end -0.2794 -0.6477)
			(stroke
				(width 0)
				(type default)
			)
			(fill no)
			(layer "B.Fab")
		)
		(pad "1" smd custom
			(at 0 -0.2794 270)
			(size 0.0762 0.0762)
			(layers "B.Cu" "B.Mask" "B.Paste")
			(net "PHY_DPB_TO_SCC_12_DN")
			(options
				(clearance outline)
				(anchor circle)
			)
			(primitives
				(gr_poly
					(pts
						(arc
							(start 0.1524 0.127)
							(mid 0.137521 0.162921)
							(end 0.1016 0.1778)
						)
						(arc
							(start -0.1016 0.1778)
							(mid -0.137521 0.162921)
							(end -0.1524 0.127)
						)
						(arc
							(start -0.1524 -0.127)
							(mid -0.137521 -0.162921)
							(end -0.1016 -0.1778)
						)
						(arc
							(start 0.1016 -0.1778)
							(mid 0.137521 -0.162921)
							(end 0.1524 -0.127)
						)
					)
					(width 0)
					(fill yes)
				)
			)
		)
		(pad "2" smd custom
			(at 0 0.2794 270)
			(size 0.0762 0.0762)
			(layers "B.Cu" "B.Mask" "B.Paste")
			(net "PHY_DPB_TO_SCC_C_12_DN")
			(options
				(clearance outline)
				(anchor circle)
			)
			(primitives
				(gr_poly
					(pts
						(arc
							(start 0.1524 0.127)
							(mid 0.137521 0.162921)
							(end 0.1016 0.1778)
						)
						(arc
							(start -0.1016 0.1778)
							(mid -0.137521 0.162921)
							(end -0.1524 0.127)
						)
						(arc
							(start -0.1524 -0.127)
							(mid -0.137521 -0.162921)
							(end -0.1016 -0.1778)
						)
						(arc
							(start 0.1016 -0.1778)
							(mid 0.137521 -0.162921)
							(end 0.1524 -0.127)
						)
					)
					(width 0)
					(fill yes)
				)
			)
		)
	)
)
